(kicad_pcb
	(version 20260206)
	(generator "pcbnew")
	(generator_version "10.0")
	(general
		(thickness 1.6)
		(legacy_teardrops no)
	)
	(paper "A4")
	(title_block
		(title "Bryce Canyon_F.DPB_16315-1-OCP.brd")
		(comment 1 "Bryce Canyon / footprints 1302-1307 of 2223")
	)
	(layers
		(0 "F.Cu" signal "TOP")
		(4 "In1.Cu" signal "L2GND")
		(6 "In2.Cu" signal "L3")
		(8 "In3.Cu" signal "L4GND")
		(10 "In4.Cu" signal "L5")
		(12 "In5.Cu" signal "L6VCC")
		(14 "In6.Cu" signal "L7VCC")
		(16 "In7.Cu" signal "L8")
		(18 "In8.Cu" signal "L9GND")
		(20 "In9.Cu" signal "L10")
		(22 "In10.Cu" signal "L11GND")
		(2 "B.Cu" signal "BOTTOM")
		(9 "F.Adhes" user "F.Adhesive")
		(11 "B.Adhes" user "B.Adhesive")
		(13 "F.Paste" user "Package Geometry/Pastemask Top")
		(15 "B.Paste" user "Package Geometry/Pastemask Bottom")
		(5 "F.SilkS" user "Ref Des/Silkscreen Top")
		(7 "B.SilkS" user "Ref Des/Silkscreen Bottom")
		(1 "F.Mask" user "Board Geometry/Soldermask Top")
		(3 "B.Mask" user "Board Geometry/Soldermask Bottom")
		(17 "Dwgs.User" user "User.Drawings")
		(19 "Cmts.User" user "User.Comments")
		(21 "Eco1.User" user "User.Eco1")
		(23 "Eco2.User" user "User.Eco2")
		(25 "Edge.Cuts" user "Board Geometry/Outline")
		(27 "Margin" user)
		(31 "F.CrtYd" user "Package Geometry/Place Bound Top")
		(29 "B.CrtYd" user "Package Geometry/Place Bound Bottom")
		(35 "F.Fab" user "Ref Des/Assembly Top")
		(33 "B.Fab" user "Ref Des/Assembly Bottom")
	)
	(footprint ""
		(layer "F.Cu")
		(at 321.634612 -44.219368 -90)
		(property "Reference" "C428"
			(at 0 0 270)
			(layer "F.SilkS")
			(hide yes)
			(effects
				(font
					(size 1.27 1.27)
				)
			)
		)
		(property "Value" "SCD01U16V1KX-GP"
			(at -2.8321 -1.7399 270)
			(unlocked yes)
			(layer "F.Fab")
			(hide yes)
			(effects
				(font
					(size 1.016 1.016)
					(thickness 0.1524)
				)
			)
		)
		(property "Device Type" "C0201H13"
			(at -2.8321 -3.2639 270)
			(unlocked yes)
			(layer "F.Fab")
			(hide yes)
			(effects
				(font
					(size 1.016 1.016)
					(thickness 0.1524)
				)
			)
		)
		(duplicate_pad_numbers_are_jumpers no)
		(fp_rect
			(start -0.2794 0.6477)
			(end 0.2794 -0.6477)
			(stroke
				(width 0)
				(type default)
			)
			(fill no)
			(layer "F.CrtYd")
		)
		(fp_rect
			(start -0.2794 0.6477)
			(end 0.2794 -0.6477)
			(stroke
				(width 0)
				(type default)
			)
			(fill no)
			(layer "F.Fab")
		)
		(pad "1" smd custom
			(at 0 -0.2794 270)
			(size 0.0762 0.0762)
			(layers "F.Cu" "F.Mask" "F.Paste")
			(net "SAS_HDD_RX_N30")
			(options
				(clearance outline)
				(anchor circle)
			)
			(primitives
				(gr_poly
					(pts
						(arc
							(start 0.1524 -0.127)
							(mid 0.137521 -0.162921)
							(end 0.1016 -0.1778)
						)
						(arc
							(start -0.1016 -0.1778)
							(mid -0.137521 -0.162921)
							(end -0.1524 -0.127)
						)
						(arc
							(start -0.1524 0.127)
							(mid -0.137521 0.162921)
							(end -0.1016 0.1778)
						)
						(arc
							(start 0.1016 0.1778)
							(mid 0.137521 0.162921)
							(end 0.1524 0.127)
						)
					)
					(width 0)
					(fill yes)
				)
			)
		)
		(pad "2" smd custom
			(at 0 0.2794 270)
			(size 0.0762 0.0762)
			(layers "F.Cu" "F.Mask" "F.Paste")
			(net "PHY_SCC_A_TO_DRV_A_30_DN")
			(options
				(clearance outline)
				(anchor circle)
			)
			(primitives
				(gr_poly
					(pts
						(arc
							(start 0.1524 -0.127)
							(mid 0.137521 -0.162921)
							(end 0.1016 -0.1778)
						)
						(arc
							(start -0.1016 -0.1778)
							(mid -0.137521 -0.162921)
							(end -0.1524 -0.127)
						)
						(arc
							(start -0.1524 0.127)
							(mid -0.137521 0.162921)
							(end -0.1016 0.1778)
						)
						(arc
							(start 0.1016 0.1778)
							(mid 0.137521 0.162921)
							(end 0.1524 0.127)
						)
					)
					(width 0)
					(fill yes)
				)
			)
		)
	)
	(footprint ""
		(layer "F.Cu")
		(at 174.5742 -52.110894 90)
		(property "Reference" "R804"
			(at 0 0 90)
			(layer "F.SilkS")
			(hide yes)
			(effects
				(font
					(size 1.27 1.27)
				)
			)
		)
		(property "Value" "4K7R2J-2-GP"
			(at 0.064008 -3.993896 90)
			(unlocked yes)
			(layer "F.Fab")
			(hide yes)
			(effects
				(font
					(size 1.016 1.016)
					(thickness 0.1524)
				)
			)
		)
		(property "Device Type" "R402H16"
			(at 0.064008 -5.517896 90)
			(unlocked yes)
			(layer "F.Fab")
			(hide yes)
			(effects
				(font
					(size 1.016 1.016)
					(thickness 0.1524)
				)
			)
		)
		(duplicate_pad_numbers_are_jumpers no)
		(fp_line
			(start 0.508 -0.9398)
			(end -0.508 -0.9398)
			(stroke
				(width 0.1524)
				(type default)
			)
			(layer "F.SilkS")
		)
		(fp_line
			(start -0.508 -0.9398)
			(end -0.508 0.9398)
			(stroke
				(width 0.1524)
				(type default)
			)
			(layer "F.SilkS")
		)
		(fp_rect
			(start -0.508 0.9398)
			(end 0.508 -0.9398)
			(stroke
				(width 0)
				(type default)
			)
			(fill no)
			(layer "F.CrtYd")
		)
		(fp_rect
			(start -0.508 0.9398)
			(end 0.508 -0.9398)
			(stroke
				(width 0)
				(type default)
			)
			(fill no)
			(layer "F.Fab")
		)
		(pad "1" smd custom
			(at 0 -0.4445 90)
			(size 0.1397 0.1397)
			(layers "F.Cu" "F.Mask" "F.Paste")
			(net "P12V_A")
			(options
				(clearance outline)
				(anchor circle)
			)
			(primitives
				(gr_poly
					(pts
						(arc
							(start -0.1778 -0.2794)
							(mid -0.249642 -0.249642)
							(end -0.2794 -0.1778)
						)
						(arc
							(start -0.2794 0.1778)
							(mid -0.249642 0.249642)
							(end -0.1778 0.2794)
						)
						(arc
							(start 0.1778 0.2794)
							(mid 0.249642 0.249642)
							(end 0.2794 0.1778)
						)
						(arc
							(start 0.2794 -0.1778)
							(mid 0.249642 -0.249642)
							(end 0.1778 -0.2794)
						)
					)
					(width 0)
					(fill yes)
				)
			)
		)
		(pad "2" smd custom
			(at 0 0.4445 90)
			(size 0.1397 0.1397)
			(layers "F.Cu" "F.Mask" "F.Paste")
			(net "SW_HDD_P29")
			(options
				(clearance outline)
				(anchor circle)
			)
			(primitives
				(gr_poly
					(pts
						(arc
							(start -0.1778 -0.2794)
							(mid -0.249642 -0.249642)
							(end -0.2794 -0.1778)
						)
						(arc
							(start -0.2794 0.1778)
							(mid -0.249642 0.249642)
							(end -0.1778 0.2794)
						)
						(arc
							(start 0.1778 0.2794)
							(mid 0.249642 0.249642)
							(end 0.2794 0.1778)
						)
						(arc
							(start 0.2794 -0.1778)
							(mid 0.249642 -0.249642)
							(end 0.1778 -0.2794)
						)
					)
					(width 0)
					(fill yes)
				)
			)
		)
	)
	(footprint ""
		(layer "F.Cu")
		(at 337.447636 -33.550352 180)
		(property "Reference" "R87"
			(at 0 0 180)
			(layer "F.SilkS")
			(hide yes)
			(effects
				(font
					(size 1.27 1.27)
				)
			)
		)
		(property "Value" "0R2J-2-GP"
			(at 0.064008 -3.993896 180)
			(unlocked yes)
			(layer "F.Fab")
			(hide yes)
			(effects
				(font
					(size 1.016 1.016)
					(thickness 0.1524)
				)
			)
		)
		(property "Device Type" "R402H16"
			(at 0.064008 -5.517896 180)
			(unlocked yes)
			(layer "F.Fab")
			(hide yes)
			(effects
				(font
					(size 1.016 1.016)
					(thickness 0.1524)
				)
			)
		)
		(duplicate_pad_numbers_are_jumpers no)
		(fp_line
			(start 0.508 -0.9398)
			(end -0.508 -0.9398)
			(stroke
				(width 0.1524)
				(type default)
			)
			(layer "F.SilkS")
		)
		(fp_line
			(start -0.508 -0.9398)
			(end -0.508 0.9398)
			(stroke
				(width 0.1524)
				(type default)
			)
			(layer "F.SilkS")
		)
		(fp_rect
			(start -0.508 0.9398)
			(end 0.508 -0.9398)
			(stroke
				(width 0)
				(type default)
			)
			(fill no)
			(layer "F.CrtYd")
		)
		(fp_rect
			(start -0.508 0.9398)
			(end 0.508 -0.9398)
			(stroke
				(width 0)
				(type default)
			)
			(fill no)
			(layer "F.Fab")
		)
		(pad "1" smd custom
			(at 0 -0.4445 180)
			(size 0.1397 0.1397)
			(layers "F.Cu" "F.Mask" "F.Paste")
			(net "IO_EXP11_SCL")
			(options
				(clearance outline)
				(anchor circle)
			)
			(primitives
				(gr_poly
					(pts
						(arc
							(start -0.1778 -0.2794)
							(mid -0.249642 -0.249642)
							(end -0.2794 -0.1778)
						)
						(arc
							(start -0.2794 0.1778)
							(mid -0.249642 0.249642)
							(end -0.1778 0.2794)
						)
						(arc
							(start 0.1778 0.2794)
							(mid 0.249642 0.249642)
							(end 0.2794 0.1778)
						)
						(arc
							(start 0.2794 -0.1778)
							(mid 0.249642 -0.249642)
							(end 0.1778 -0.2794)
						)
					)
					(width 0)
					(fill yes)
				)
			)
		)
		(pad "2" smd custom
			(at 0 0.4445 180)
			(size 0.1397 0.1397)
			(layers "F.Cu" "F.Mask" "F.Paste")
			(net "I2C_BMC_B_MISC_SCL")
			(options
				(clearance outline)
				(anchor circle)
			)
			(primitives
				(gr_poly
					(pts
						(arc
							(start -0.1778 -0.2794)
							(mid -0.249642 -0.249642)
							(end -0.2794 -0.1778)
						)
						(arc
							(start -0.2794 0.1778)
							(mid -0.249642 0.249642)
							(end -0.1778 0.2794)
						)
						(arc
							(start 0.1778 0.2794)
							(mid 0.249642 0.249642)
							(end 0.2794 0.1778)
						)
						(arc
							(start 0.2794 -0.1778)
							(mid 0.249642 -0.249642)
							(end 0.1778 -0.2794)
						)
					)
					(width 0)
					(fill yes)
				)
			)
		)
	)
	(footprint ""
		(layer "F.Cu")
		(at 479.298 -297.372024)
		(property "Reference" "TP57"
			(at 0 0 0)
			(layer "F.SilkS")
			(hide yes)
			(effects
				(font
					(size 1.27 1.27)
				)
			)
		)
		(property "Value" "TPAD32-GP"
			(at -0.0508 -1.6764 0)
			(unlocked yes)
			(layer "F.Fab")
			(hide yes)
			(effects
				(font
					(size 1.016 1.016)
					(thickness 0.1524)
				)
			)
		)
		(property "Device Type" "TPAD32"
			(at -0.0508 -3.2004 0)
			(unlocked yes)
			(layer "F.Fab")
			(hide yes)
			(effects
				(font
					(size 1.016 1.016)
					(thickness 0.1524)
				)
			)
		)
		(duplicate_pad_numbers_are_jumpers no)
		(fp_poly
			(pts
				(arc
					(start 0.4064 0)
					(mid -0.4064 0)
					(end 0.4064 0)
				)
			)
			(stroke
				(width 0)
				(type default)
			)
			(fill no)
			(layer "F.CrtYd")
		)
		(fp_poly
			(pts
				(arc
					(start 0.7112 0)
					(mid -0.7112 0)
					(end 0.7112 0)
				)
			)
			(stroke
				(width 0)
				(type default)
			)
			(fill no)
			(layer "F.Fab")
		)
		(pad "1" smd circle
			(at 0 0)
			(size 0.8128 0.8128)
			(layers "F.Cu" "F.Mask" "F.Paste")
			(net "ACT_HDD_11")
		)
	)
	(footprint ""
		(layer "F.Cu")
		(at 412.323534 -290.148518)
		(property "Reference" "Q262"
			(at 0 0 0)
			(layer "F.SilkS")
			(hide yes)
			(effects
				(font
					(size 1.27 1.27)
				)
			)
		)
		(property "Value" "2N7002K-2-GP"
			(at 0.127 -8.9662 0)
			(unlocked yes)
			(layer "F.Fab")
			(hide yes)
			(effects
				(font
					(size 1.016 1.016)
					(thickness 0.1524)
				)
			)
		)
		(property "Device Type" "SOT23DGS2D4H44"
			(at 0.127 -10.4902 0)
			(unlocked yes)
			(layer "F.Fab")
			(hide yes)
			(effects
				(font
					(size 1.016 1.016)
					(thickness 0.1524)
				)
			)
		)
		(duplicate_pad_numbers_are_jumpers no)
		(fp_line
			(start -1.651 -1.778)
			(end -1.651 1.778)
			(stroke
				(width 0.1524)
				(type default)
			)
			(layer "F.SilkS")
		)
		(fp_line
			(start -1.651 1.778)
			(end 1.651 1.778)
			(stroke
				(width 0.1524)
				(type default)
			)
			(layer "F.SilkS")
		)
		(fp_line
			(start 1.651 -1.778)
			(end -1.651 -1.778)
			(stroke
				(width 0.1524)
				(type default)
			)
			(layer "F.SilkS")
		)
		(fp_line
			(start 1.651 1.778)
			(end 1.651 -1.778)
			(stroke
				(width 0.1524)
				(type default)
			)
			(layer "F.SilkS")
		)
		(fp_poly
			(pts
				(xy -1.778 1.8796) (xy -1.778 -1.8796) (xy 1.778 -1.8796) (xy 1.778 1.8796)
			)
			(stroke
				(width 0)
				(type default)
			)
			(fill no)
			(layer "F.CrtYd")
		)
		(fp_poly
			(pts
				(xy -1.778 1.8796) (xy -1.778 -1.8796) (xy 1.778 -1.8796) (xy 1.778 1.8796)
			)
			(stroke
				(width 0)
				(type default)
			)
			(fill no)
			(layer "F.Fab")
		)
		(pad "D" smd custom
			(at 0 -0.9525)
			(size 0.1905 0.1905)
			(layers "F.Cu" "F.Mask" "F.Paste")
			(net "FLT_HDD33_N")
			(options
				(clearance outline)
				(anchor circle)
			)
			(primitives
				(gr_poly
					(pts
						(arc
							(start -0.1778 0.5715)
							(mid -0.321484 0.511984)
							(end -0.381 0.3683)
						)
						(arc
							(start -0.381 -0.3683)
							(mid -0.321484 -0.511984)
							(end -0.1778 -0.5715)
						)
						(arc
							(start 0.1778 -0.5715)
							(mid 0.321484 -0.511984)
							(end 0.381 -0.3683)
						)
						(arc
							(start 0.381 0.3683)
							(mid 0.321484 0.511984)
							(end 0.1778 0.5715)
						)
					)
					(width 0)
					(fill yes)
				)
			)
		)
		(pad "G" smd custom
			(at -0.98425 0.9525)
			(size 0.1905 0.1905)
			(layers "F.Cu" "F.Mask" "F.Paste")
			(net "DRIVE_B_33_FLT_LED")
			(options
				(clearance outline)
				(anchor circle)
			)
			(primitives
				(gr_poly
					(pts
						(arc
							(start -0.1778 0.5715)
							(mid -0.321484 0.511984)
							(end -0.381 0.3683)
						)
						(arc
							(start -0.381 -0.3683)
							(mid -0.321484 -0.511984)
							(end -0.1778 -0.5715)
						)
						(arc
							(start 0.1778 -0.5715)
							(mid 0.321484 -0.511984)
							(end 0.381 -0.3683)
						)
						(arc
							(start 0.381 0.3683)
							(mid 0.321484 0.511984)
							(end 0.1778 0.5715)
						)
					)
					(width 0)
					(fill yes)
				)
			)
		)
		(pad "S" smd custom
			(at 0.98425 0.9525)
			(size 0.1905 0.1905)
			(layers "F.Cu" "F.Mask" "F.Paste")
			(net "GND")
			(options
				(clearance outline)
				(anchor circle)
			)
			(primitives
				(gr_poly
					(pts
						(arc
							(start -0.1778 0.5715)
							(mid -0.321484 0.511984)
							(end -0.381 0.3683)
						)
						(arc
							(start -0.381 -0.3683)
							(mid -0.321484 -0.511984)
							(end -0.1778 -0.5715)
						)
						(arc
							(start 0.1778 -0.5715)
							(mid 0.321484 -0.511984)
							(end 0.381 -0.3683)
						)
						(arc
							(start 0.381 0.3683)
							(mid 0.321484 0.511984)
							(end 0.1778 0.5715)
						)
					)
					(width 0)
					(fill yes)
				)
			)
		)
	)
	(footprint ""
		(layer "F.Cu")
		(at 224.3836 -205.646528 180)
		(property "Reference" "R609"
			(at 0 0 180)
			(layer "F.SilkS")
			(hide yes)
			(effects
				(font
					(size 1.27 1.27)
				)
			)
		)
		(property "Value" "2K2R2F-GP"
			(at 0.064008 -3.993896 180)
			(unlocked yes)
			(layer "F.Fab")
			(hide yes)
			(effects
				(font
					(size 1.016 1.016)
					(thickness 0.1524)
				)
			)
		)
		(property "Device Type" "R402H16"
			(at 0.064008 -5.517896 180)
			(unlocked yes)
			(layer "F.Fab")
			(hide yes)
			(effects
				(font
					(size 1.016 1.016)
					(thickness 0.1524)
				)
			)
		)
		(duplicate_pad_numbers_are_jumpers no)
		(fp_line
			(start 0.508 -0.9398)
			(end -0.508 -0.9398)
			(stroke
				(width 0.1524)
				(type default)
			)
			(layer "F.SilkS")
		)
		(fp_line
			(start -0.508 -0.9398)
			(end -0.508 0.9398)
			(stroke
				(width 0.1524)
				(type default)
			)
			(layer "F.SilkS")
		)
		(fp_rect
			(start -0.508 0.9398)
			(end 0.508 -0.9398)
			(stroke
				(width 0)
				(type default)
			)
			(fill no)
			(layer "F.CrtYd")
		)
		(fp_rect
			(start -0.508 0.9398)
			(end 0.508 -0.9398)
			(stroke
				(width 0)
				(type default)
			)
			(fill no)
			(layer "F.Fab")
		)
		(pad "1" smd custom
			(at 0 -0.4445 180)
			(size 0.1397 0.1397)
			(layers "F.Cu" "F.Mask" "F.Paste")
			(net "P3V3_STBY_A")
			(options
				(clearance outline)
				(anchor circle)
			)
			(primitives
				(gr_poly
					(pts
						(arc
							(start -0.1778 -0.2794)
							(mid -0.249642 -0.249642)
							(end -0.2794 -0.1778)
						)
						(arc
							(start -0.2794 0.1778)
							(mid -0.249642 0.249642)
							(end -0.1778 0.2794)
						)
						(arc
							(start 0.1778 0.2794)
							(mid 0.249642 0.249642)
							(end 0.2794 0.1778)
						)
						(arc
							(start 0.2794 -0.1778)
							(mid 0.249642 -0.249642)
							(end 0.1778 -0.2794)
						)
					)
					(width 0)
					(fill yes)
				)
			)
		)
		(pad "2" smd custom
			(at 0 0.4445 180)
			(size 0.1397 0.1397)
			(layers "F.Cu" "F.Mask" "F.Paste")
			(net "I2C_SCC_A_SCL")
			(options
				(clearance outline)
				(anchor circle)
			)
			(primitives
				(gr_poly
					(pts
						(arc
							(start -0.1778 -0.2794)
							(mid -0.249642 -0.249642)
							(end -0.2794 -0.1778)
						)
						(arc
							(start -0.2794 0.1778)
							(mid -0.249642 0.249642)
							(end -0.1778 0.2794)
						)
						(arc
							(start 0.1778 0.2794)
							(mid 0.249642 0.249642)
							(end 0.2794 0.1778)
						)
						(arc
							(start 0.2794 -0.1778)
							(mid 0.249642 -0.249642)
							(end 0.1778 -0.2794)
						)
					)
					(width 0)
					(fill yes)
				)
			)
		)
	)
)
